(kicad_pcb
	(version 20241229)
	(generator "pcbnew")
	(generator_version "9.0")
	(general
		(thickness 1.711)
		(legacy_teardrops no)
	)
	(paper "A4")
	(title_block
		(title "Antmicro Baseboard for Jetson AGX Thor")
		(date "2026-02-18")
		(rev "1.1.0")
		(company "Antmicro Ltd")
		(comment 1 "www.antmicro.com")
		(comment 9 "footprints 562-565 of 1170")
	)
	(layers
		(0 "F.Cu" signal)
		(4 "In1.Cu" signal)
		(6 "In2.Cu" signal)
		(8 "In3.Cu" signal)
		(10 "In4.Cu" jumper)
		(12 "In5.Cu" signal)
		(14 "In6.Cu" signal)
		(16 "In7.Cu" signal)
		(18 "In8.Cu" signal)
		(2 "B.Cu" signal)
		(9 "F.Adhes" user "F.Adhesive")
		(11 "B.Adhes" user "B.Adhesive")
		(13 "F.Paste" user)
		(15 "B.Paste" user)
		(5 "F.SilkS" user "F.Silkscreen")
		(7 "B.SilkS" user "B.Silkscreen")
		(1 "F.Mask" user)
		(3 "B.Mask" user)
		(17 "Dwgs.User" user "User.Drawings")
		(19 "Cmts.User" user "User.Comments")
		(21 "Eco1.User" user "User.Eco1")
		(23 "Eco2.User" user "User.Eco2")
		(25 "Edge.Cuts" user)
		(27 "Margin" user)
		(31 "F.CrtYd" user "F.Courtyard")
		(29 "B.CrtYd" user "B.Courtyard")
		(35 "F.Fab" user)
		(33 "B.Fab" user)
	)
	(footprint "antmicro-footprints:R_0603_1608Metric"
		(layer "F.Cu")
		(at 147.944391 124.83 180)
		(descr "Resistor SMD 0603")
		(tags "resistor SMD 0603")
		(property "Reference" "R10"
			(at -3.355609 0.33 0)
			(layer "F.SilkS")
			(effects
				(font
					(size 0.7 0.7)
					(thickness 0.15)
				)
				(justify right top)
			)
		)
		(property "Value" "R_0R_22.4A_0603"
			(at 0 1.6 0)
			(layer "F.Fab")
			(effects
				(font
					(size 0.7 0.7)
					(thickness 0.15)
				)
				(justify right top)
			)
		)
		(property "Datasheet" "https://fscdn.rohm.com/en/products/databook/datasheet/passive/resistor/chip_resistor/pmr-jpw-e.pdf"
			(at 0 0 0)
			(layer "F.Fab")
			(hide yes)
			(effects
				(font
					(size 1.27 1.27)
					(thickness 0.15)
				)
			)
		)
		(property "Description" "SMD Chip Resistor"
			(at 0 0 0)
			(layer "F.Fab")
			(hide yes)
			(effects
				(font
					(size 1.27 1.27)
					(thickness 0.15)
				)
			)
		)
		(property "Manufacturer" "ROHM Semiconductor"
			(at 0 0 180)
			(unlocked yes)
			(layer "F.Fab")
			(hide yes)
			(effects
				(font
					(size 1 1)
					(thickness 0.15)
				)
			)
		)
		(property "MPN" "PMR03EZPJ000"
			(at 0 0 180)
			(unlocked yes)
			(layer "F.Fab")
			(hide yes)
			(effects
				(font
					(size 1 1)
					(thickness 0.15)
				)
			)
		)
		(property "Val" "0R"
			(at 0 0 180)
			(unlocked yes)
			(layer "F.Fab")
			(hide yes)
			(effects
				(font
					(size 1 1)
					(thickness 0.15)
				)
			)
		)
		(property "Author" "Antmicro"
			(at 0 0 180)
			(unlocked yes)
			(layer "F.Fab")
			(hide yes)
			(effects
				(font
					(size 1 1)
					(thickness 0.15)
				)
			)
		)
		(property "License" "Apache-2.0"
			(at 0 0 180)
			(unlocked yes)
			(layer "F.Fab")
			(hide yes)
			(effects
				(font
					(size 1 1)
					(thickness 0.15)
				)
			)
		)
		(property "Max. Curr." "22.4A"
			(at 0 0 180)
			(unlocked yes)
			(layer "F.Fab")
			(hide yes)
			(effects
				(font
					(size 1 1)
					(thickness 0.15)
				)
			)
		)
		(property "Tolerance" "template_tolerance"
			(at 0 0 180)
			(unlocked yes)
			(layer "F.Fab")
			(hide yes)
			(effects
				(font
					(size 1 1)
					(thickness 0.15)
				)
			)
		)
		(component_classes
			(class "DCDC_1V8")
		)
		(sheetname "/DCDC/")
		(sheetfile "dcdc.kicad_sch")
		(attr smd)
		(fp_line
			(start -0.15 0.4)
			(end 0.15 0.4)
			(stroke
				(width 0.15)
				(type solid)
			)
			(layer "F.SilkS")
		)
		(fp_line
			(start -0.15 -0.4)
			(end 0.15 -0.4)
			(stroke
				(width 0.15)
				(type solid)
			)
			(layer "F.SilkS")
		)
		(fp_rect
			(start -1.25 -0.65)
			(end 1.25 0.65)
			(stroke
				(width 0.05)
				(type solid)
			)
			(fill no)
			(layer "F.CrtYd")
		)
		(fp_rect
			(start -0.8 -0.4)
			(end 0.8 0.4)
			(stroke
				(width 0.15)
				(type solid)
			)
			(fill no)
			(layer "F.Fab")
		)
		(fp_text user "${REFERENCE}"
			(at -1.25 3.898 0)
			(layer "F.Fab")
			(effects
				(font
					(size 0.7 0.7)
					(thickness 0.15)
				)
				(justify right top)
			)
		)
		(fp_text user "License: Apache-2.0"
			(at -1.25 5.9 0)
			(layer "F.Fab")
			(effects
				(font
					(size 0.7 0.7)
					(thickness 0.15)
				)
				(justify right top)
			)
		)
		(fp_text user "Author: Antmicro"
			(at -1.25 4.9 0)
			(layer "F.Fab")
			(effects
				(font
					(size 0.7 0.7)
					(thickness 0.15)
				)
				(justify right top)
			)
		)
		(pad "1" smd roundrect
			(at -0.7 0 180)
			(size 0.8 1)
			(layers "F.Cu" "F.Mask" "F.Paste")
			(roundrect_rratio 0.2)
			(net 17 "/DCDC/1V8_OUT")
			(pintype "passive")
		)
		(pad "2" smd roundrect
			(at 0.7 0 180)
			(size 0.8 1)
			(layers "F.Cu" "F.Mask" "F.Paste")
			(roundrect_rratio 0.2)
			(net 11 "+1V8")
			(pintype "passive")
		)
	)
	(footprint "antmicro-footprints:C_0402_1005Metric"
		(layer "F.Cu")
		(at 195.25 57.25 90)
		(descr "Capacitor SMD 0402")
		(tags "capacitor SMD 0402")
		(property "Reference" "C39"
			(at -1.65 -0.55 90)
			(layer "F.SilkS")
			(effects
				(font
					(size 0.7 0.7)
					(thickness 0.15)
				)
				(justify left bottom)
			)
		)
		(property "Value" "C_100n_0402"
			(at -1.022927 2.155213 90)
			(layer "F.Fab")
			(effects
				(font
					(size 0.7 0.7)
					(thickness 0.15)
				)
				(justify left bottom)
			)
		)
		(property "Datasheet" "https://www.murata.com/products/productdetail?partno=GRM155R61H104KE14%23"
			(at 0 0 90)
			(layer "F.Fab")
			(hide yes)
			(effects
				(font
					(size 1.27 1.27)
					(thickness 0.15)
				)
			)
		)
		(property "Description" "SMD Multilayer Ceramic Capacitor, 0.1 µF, 50 V, 0402 [1005 Metric], ± 10%, X5R, GRM Series"
			(at 0 0 90)
			(layer "F.Fab")
			(hide yes)
			(effects
				(font
					(size 1.27 1.27)
					(thickness 0.15)
				)
			)
		)
		(property "Manufacturer" "Murata"
			(at 0 0 90)
			(unlocked yes)
			(layer "F.Fab")
			(hide yes)
			(effects
				(font
					(size 1 1)
					(thickness 0.15)
				)
			)
		)
		(property "MPN" "GRM155R61H104KE14D"
			(at 0 0 90)
			(unlocked yes)
			(layer "F.Fab")
			(hide yes)
			(effects
				(font
					(size 1 1)
					(thickness 0.15)
				)
			)
		)
		(property "Val" "100n"
			(at 0 0 90)
			(unlocked yes)
			(layer "F.Fab")
			(hide yes)
			(effects
				(font
					(size 1 1)
					(thickness 0.15)
				)
			)
		)
		(property "License" "Apache-2.0"
			(at 0 0 90)
			(unlocked yes)
			(layer "F.Fab")
			(hide yes)
			(effects
				(font
					(size 1 1)
					(thickness 0.15)
				)
			)
		)
		(property "Author" "Antmicro"
			(at 0 0 90)
			(unlocked yes)
			(layer "F.Fab")
			(hide yes)
			(effects
				(font
					(size 1 1)
					(thickness 0.15)
				)
			)
		)
		(property "Voltage" "50V"
			(at 0 0 90)
			(unlocked yes)
			(layer "F.Fab")
			(hide yes)
			(effects
				(font
					(size 1 1)
					(thickness 0.15)
				)
			)
		)
		(property "Dielectric" "X5R"
			(at 0 0 90)
			(unlocked yes)
			(layer "F.Fab")
			(hide yes)
			(effects
				(font
					(size 1 1)
					(thickness 0.15)
				)
			)
		)
		(sheetname "/SoM_Power/")
		(sheetfile "som_power.kicad_sch")
		(attr smd)
		(fp_poly
			(pts
				(xy -0.925 -0.47) (xy 0.925 -0.47) (xy 0.925 0.47) (xy -0.925 0.47)
			)
			(stroke
				(width 0.05)
				(type default)
			)
			(fill no)
			(layer "F.CrtYd")
		)
		(fp_line
			(start 0.504 -0.25)
			(end 0.504 0.248)
			(stroke
				(width 0.15)
				(type solid)
			)
			(layer "F.Fab")
		)
		(fp_line
			(start -0.494 -0.25)
			(end 0.504 -0.25)
			(stroke
				(width 0.15)
				(type solid)
			)
			(layer "F.Fab")
		)
		(fp_line
			(start 0.504 0.248)
			(end -0.494 0.248)
			(stroke
				(width 0.15)
				(type solid)
			)
			(layer "F.Fab")
		)
		(fp_line
			(start -0.494 0.248)
			(end -0.494 -0.25)
			(stroke
				(width 0.15)
				(type solid)
			)
			(layer "F.Fab")
		)
		(fp_text user "License: Apache-2.0"
			(at -0.939 5.799 90)
			(layer "F.Fab")
			(effects
				(font
					(size 0.7 0.7)
					(thickness 0.15)
				)
				(justify left bottom)
			)
		)
		(fp_text user "${REFERENCE}"
			(at -0.939 4.599 90)
			(layer "F.Fab")
			(effects
				(font
					(size 0.7 0.7)
					(thickness 0.15)
				)
				(justify left bottom)
			)
		)
		(fp_text user "Author: Antmicro"
			(at -0.939 3.399 90)
			(layer "F.Fab")
			(effects
				(font
					(size 0.7 0.7)
					(thickness 0.15)
				)
				(justify left bottom)
			)
		)
		(pad "1" smd roundrect
			(at -0.48 0 90)
			(size 0.59 0.64)
			(layers "F.Cu" "F.Mask" "F.Paste")
			(roundrect_rratio 0.25)
			(net 1 "GND")
			(pintype "passive")
		)
		(pad "2" smd roundrect
			(at 0.48 0 90)
			(size 0.59 0.64)
			(layers "F.Cu" "F.Mask" "F.Paste")
			(roundrect_rratio 0.25)
			(net 702 "/SoM_Power/~{SYS_RESET}")
			(pintype "passive")
		)
	)
	(footprint "antmicro-footprints:Oscillator_SMD_Abracon_AX3_3.2x2.5x1mm"
		(layer "F.Cu")
		(at 87.37 148.090499)
		(property "Reference" "Y1"
			(at -0.319502 2.000001 0)
			(layer "F.SilkS")
			(effects
				(font
					(size 0.7 0.7)
					(thickness 0.15)
				)
				(justify right top)
			)
		)
		(property "Value" "Oscillator_100MHz_NX324"
			(at 0 2.8 0)
			(layer "F.Fab")
			(effects
				(font
					(size 0.7 0.7)
					(thickness 0.15)
				)
				(justify left bottom)
			)
		)
		(property "Datasheet" "https://www.diodes.com/assets/Datasheets/NX324.pdf"
			(at 0 0 0)
			(layer "F.Fab")
			(hide yes)
			(effects
				(font
					(size 1.27 1.27)
					(thickness 0.15)
				)
			)
		)
		(property "Description" "100 MHz XO (Standard) HCSL Oscillator 3.3V Enable/Disable 6-SMD, No Lead"
			(at 0 0 0)
			(layer "F.Fab")
			(hide yes)
			(effects
				(font
					(size 1.27 1.27)
					(thickness 0.15)
				)
			)
		)
		(property "Manufacturer" "Diodes Incorporated"
			(at 0 0 180)
			(unlocked yes)
			(layer "F.Fab")
			(hide yes)
			(effects
				(font
					(size 1 1)
					(thickness 0.15)
				)
			)
		)
		(property "MPN" "NX3241E0100.000000"
			(at 0 0 180)
			(unlocked yes)
			(layer "F.Fab")
			(hide yes)
			(effects
				(font
					(size 1 1)
					(thickness 0.15)
				)
			)
		)
		(property "Val" "100 MHz"
			(at 0 0 180)
			(unlocked yes)
			(layer "F.Fab")
			(hide yes)
			(effects
				(font
					(size 1 1)
					(thickness 0.15)
				)
			)
		)
		(property "Author" "Antmicro"
			(at 0 0 180)
			(unlocked yes)
			(layer "F.Fab")
			(hide yes)
			(effects
				(font
					(size 1 1)
					(thickness 0.15)
				)
			)
		)
		(property "License" "Apache-2.0"
			(at 0 0 180)
			(unlocked yes)
			(layer "F.Fab")
			(hide yes)
			(effects
				(font
					(size 1 1)
					(thickness 0.15)
				)
			)
		)
		(sheetname "/SoM_IO2/")
		(sheetfile "som_io2.kicad_sch")
		(attr smd)
		(fp_line
			(start -1.5 -1.8)
			(end -1.5 -1.5)
			(stroke
				(width 0.12)
				(type solid)
			)
			(layer "F.SilkS")
		)
		(fp_line
			(start -1.5 1.5)
			(end -1.5 1.8)
			(stroke
				(width 0.12)
				(type solid)
			)
			(layer "F.SilkS")
		)
		(fp_line
			(start -1.5 1.8)
			(end 1.5 1.8)
			(stroke
				(width 0.12)
				(type solid)
			)
			(layer "F.SilkS")
		)
		(fp_line
			(start 1.5 -1.8)
			(end -1.5 -1.8)
			(stroke
				(width 0.12)
				(type solid)
			)
			(layer "F.SilkS")
		)
		(fp_line
			(start 1.5 -1.5)
			(end 1.5 -1.8)
			(stroke
				(width 0.12)
				(type solid)
			)
			(layer "F.SilkS")
		)
		(fp_line
			(start 1.5 1.8)
			(end 1.5 1.5)
			(stroke
				(width 0.12)
				(type solid)
			)
			(layer "F.SilkS")
		)
		(fp_circle
			(center -1.7 -1.899999)
			(end -1.7 -1.85)
			(stroke
				(width 0.15)
				(type solid)
			)
			(fill yes)
			(layer "F.SilkS")
		)
		(fp_poly
			(pts
				(xy 1.6 -1.9) (xy 1.6 1.9) (xy -1.6 1.9) (xy -1.6 -1.9)
			)
			(stroke
				(width 0.05)
				(type solid)
			)
			(fill no)
			(layer "F.CrtYd")
		)
		(fp_line
			(start -0.6 -1.6)
			(end -1.3 -0.9)
			(stroke
				(width 0.15)
				(type solid)
			)
			(layer "F.Fab")
		)
		(fp_poly
			(pts
				(xy 1.3 -1.601) (xy 1.3 1.599) (xy -1.3 1.599) (xy -1.3 -1.601)
			)
			(stroke
				(width 0.15)
				(type solid)
			)
			(fill no)
			(layer "F.Fab")
		)
		(fp_text user "License: Apache-2.0"
			(at -1.6 6.499 0)
			(layer "F.Fab")
			(effects
				(font
					(size 0.7 0.7)
					(thickness 0.15)
				)
				(justify left bottom)
			)
		)
		(fp_text user "${REFERENCE}"
			(at -1.6 4.1 0)
			(layer "F.Fab")
			(effects
				(font
					(size 0.7 0.7)
					(thickness 0.15)
				)
				(justify left bottom)
			)
		)
		(fp_text user "Author: Antmicro"
			(at -1.6 5.3 0)
			(layer "F.Fab")
			(effects
				(font
					(size 0.7 0.7)
					(thickness 0.15)
				)
				(justify left bottom)
			)
		)
		(pad "1" smd rect
			(at -0.799999 -1.199 270)
			(size 0.9 1.1)
			(layers "F.Cu" "F.Mask" "F.Paste")
			(net 893 "Net-(Y1-EN)")
			(pinfunction "EN")
			(pintype "input")
		)
		(pad "2" smd rect
			(at -0.799999 0 270)
			(size 0.9 1.1)
			(layers "F.Cu" "F.Mask" "F.Paste")
			(net 1125 "unconnected-(Y1-NC-Pad2)")
			(pinfunction "NC")
			(pintype "no_connect")
		)
		(pad "3" smd rect
			(at -0.799999 1.199 270)
			(size 0.9 1.1)
			(layers "F.Cu" "F.Mask" "F.Paste")
			(net 1 "GND")
			(pinfunction "GND")
			(pintype "power_in")
		)
		(pad "4" smd rect
			(at 0.801001 1.199 270)
			(size 0.9 1.1)
			(layers "F.Cu" "F.Mask" "F.Paste")
			(net 897 "/SoM_IO2/C2_CLK+")
			(pinfunction "OUT+")
			(pintype "output")
		)
		(pad "5" smd rect
			(at 0.801001 0 270)
			(size 0.9 1.1)
			(layers "F.Cu" "F.Mask" "F.Paste")
			(net 1001 "/SoM_IO2/C2_CLK-")
			(pinfunction "OUT-")
			(pintype "output")
		)
		(pad "6" smd rect
			(at 0.801001 -1.199 270)
			(size 0.9 1.1)
			(layers "F.Cu" "F.Mask" "F.Paste")
			(net 2 "+3V3")
			(pinfunction "VCC")
			(pintype "power_in")
		)
	)
	(footprint "antmicro-footprints:C_0402_1005Metric"
		(layer "F.Cu")
		(at 219.124 104.225 180)
		(descr "Capacitor SMD 0402")
		(tags "capacitor SMD 0402")
		(property "Reference" "C109"
			(at -1.37 1.475 0)
			(layer "F.SilkS")
			(effects
				(font
					(size 0.7 0.7)
					(thickness 0.15)
				)
				(justify right top)
			)
		)
		(property "Value" "C_100n_0402"
			(at -1.022927 2.155213 0)
			(layer "F.Fab")
			(effects
				(font
					(size 0.7 0.7)
					(thickness 0.15)
				)
				(justify right top)
			)
		)
		(property "Datasheet" "https://www.murata.com/products/productdetail?partno=GRM155R61H104KE14%23"
			(at 0 0 0)
			(layer "F.Fab")
			(hide yes)
			(effects
				(font
					(size 1.27 1.27)
					(thickness 0.15)
				)
			)
		)
		(property "Description" "SMD Multilayer Ceramic Capacitor, 0.1 µF, 50 V, 0402 [1005 Metric], ± 10%, X5R, GRM Series"
			(at 0 0 0)
			(layer "F.Fab")
			(hide yes)
			(effects
				(font
					(size 1.27 1.27)
					(thickness 0.15)
				)
			)
		)
		(property "Manufacturer" "Murata"
			(at 0 0 180)
			(unlocked yes)
			(layer "F.Fab")
			(hide yes)
			(effects
				(font
					(size 1 1)
					(thickness 0.15)
				)
			)
		)
		(property "MPN" "GRM155R61H104KE14D"
			(at 0 0 180)
			(unlocked yes)
			(layer "F.Fab")
			(hide yes)
			(effects
				(font
					(size 1 1)
					(thickness 0.15)
				)
			)
		)
		(property "Val" "100n"
			(at 0 0 180)
			(unlocked yes)
			(layer "F.Fab")
			(hide yes)
			(effects
				(font
					(size 1 1)
					(thickness 0.15)
				)
			)
		)
		(property "License" "Apache-2.0"
			(at 0 0 180)
			(unlocked yes)
			(layer "F.Fab")
			(hide yes)
			(effects
				(font
					(size 1 1)
					(thickness 0.15)
				)
			)
		)
		(property "Author" "Antmicro"
			(at 0 0 180)
			(unlocked yes)
			(layer "F.Fab")
			(hide yes)
			(effects
				(font
					(size 1 1)
					(thickness 0.15)
				)
			)
		)
		(property "Voltage" "50V"
			(at 0 0 180)
			(unlocked yes)
			(layer "F.Fab")
			(hide yes)
			(effects
				(font
					(size 1 1)
					(thickness 0.15)
				)
			)
		)
		(property "Dielectric" "X5R"
			(at 0 0 180)
			(unlocked yes)
			(layer "F.Fab")
			(hide yes)
			(effects
				(font
					(size 1 1)
					(thickness 0.15)
				)
			)
		)
		(sheetname "/Recovery USB/")
		(sheetfile "recovery_usb.kicad_sch")
		(attr smd)
		(fp_rect
			(start -0.925 -0.47)
			(end 0.925 0.47)
			(stroke
				(width 0.05)
				(type default)
			)
			(fill no)
			(layer "F.CrtYd")
		)
		(fp_line
			(start 0.504 0.248)
			(end -0.494 0.248)
			(stroke
				(width 0.15)
				(type solid)
			)
			(layer "F.Fab")
		)
		(fp_line
			(start 0.504 -0.25)
			(end 0.504 0.248)
			(stroke
				(width 0.15)
				(type solid)
			)
			(layer "F.Fab")
		)
		(fp_line
			(start -0.494 0.248)
			(end -0.494 -0.25)
			(stroke
				(width 0.15)
				(type solid)
			)
			(layer "F.Fab")
		)
		(fp_line
			(start -0.494 -0.25)
			(end 0.504 -0.25)
			(stroke
				(width 0.15)
				(type solid)
			)
			(layer "F.Fab")
		)
		(fp_text user "Author: Antmicro"
			(at -0.939 3.399 0)
			(layer "F.Fab")
			(effects
				(font
					(size 0.7 0.7)
					(thickness 0.15)
				)
				(justify right top)
			)
		)
		(fp_text user "${REFERENCE}"
			(at -0.939 4.599 0)
			(layer "F.Fab")
			(effects
				(font
					(size 0.7 0.7)
					(thickness 0.15)
				)
				(justify right top)
			)
		)
		(fp_text user "License: Apache-2.0"
			(at -0.939 5.799 0)
			(layer "F.Fab")
			(effects
				(font
					(size 0.7 0.7)
					(thickness 0.15)
				)
				(justify right top)
			)
		)
		(pad "1" smd roundrect
			(at -0.48 0 180)
			(size 0.59 0.64)
			(layers "F.Cu" "F.Mask" "F.Paste")
			(roundrect_rratio 0.25)
			(net 245 "/Recovery USB/USBC2_CONN_TX1_P")
			(pintype "passive")
		)
		(pad "2" smd roundrect
			(at 0.48 0 180)
			(size 0.59 0.64)
			(layers "F.Cu" "F.Mask" "F.Paste")
			(roundrect_rratio 0.25)
			(net 242 "/Recovery USB/USBC2_TX1_P")
			(pintype "passive")
		)
	)
)
